(kicad_sch
	(version 20250114)
	(generator "eeschema")
	(generator_version "9.0")
	(paper "A3")
	(title_block
		(title "OCuLink to 10GbE adapter")
		(date "2026-02-23")
		(rev "1.1.0")
		(company "Antmicro Ltd")
		(comment 1 "www.antmicro.com")
	)
	(rectangle
		(start 139.7 88.9)
		(end 292.1 190.5)
		(stroke
			(width 0.127)
			(type solid)
		)
		(fill
			(type color)
			(color 255 255 194 0.2)
		)
	)
	(text "X710-AT2"
		(exclude_from_sim no)
		(at 151.13 92.71 0)
		(effects
			(font
				(size 2.54 2.54)
				(thickness 0.508)
				(bold yes)
			)
		)
	)
	(junction
		(at 355.6 210.82)
		(diameter 0)
		(color 0 0 0 0)
	)
	(junction
		(at 317.5 218.44)
		(diameter 0)
		(color 0 0 0 0)
	)
	(junction
		(at 149.86 160.02)
		(diameter 0)
		(color 0 0 0 0)
	)
	(junction
		(at 317.5 226.06)
		(diameter 0)
		(color 0 0 0 0)
	)
	(junction
		(at 317.5 210.82)
		(diameter 0)
		(color 0 0 0 0)
	)
	(junction
		(at 355.6 226.06)
		(diameter 0)
		(color 0 0 0 0)
	)
	(junction
		(at 355.6 218.44)
		(diameter 0)
		(color 0 0 0 0)
	)
	(wire
		(pts
			(xy 279.4 109.22) (xy 304.8 109.22)
		)
		(stroke
			(width 0)
			(type default)
		)
	)
	(wire
		(pts
			(xy 355.6 218.44) (xy 355.6 226.06)
		)
		(stroke
			(width 0)
			(type default)
		)
	)
	(wire
		(pts
			(xy 76.2 160.02) (xy 149.86 160.02)
		)
		(stroke
			(width 0)
			(type default)
		)
	)
	(wire
		(pts
			(xy 152.4 137.16) (xy 149.86 137.16)
		)
		(stroke
			(width 0)
			(type default)
		)
	)
	(wire
		(pts
			(xy 355.6 203.2) (xy 355.6 210.82)
		)
		(stroke
			(width 0)
			(type default)
		)
	)
	(wire
		(pts
			(xy 317.5 226.06) (xy 317.5 228.6)
		)
		(stroke
			(width 0)
			(type default)
		)
	)
	(wire
		(pts
			(xy 298.45 134.62) (xy 203.2 134.62)
		)
		(stroke
			(width 0)
			(type default)
		)
	)
	(wire
		(pts
			(xy 88.9 95.25) (xy 88.9 157.48)
		)
		(stroke
			(width 0)
			(type default)
		)
	)
	(bus
		(pts
			(xy 76.2 134.62) (xy 152.4 134.62)
		)
		(stroke
			(width 0)
			(type default)
		)
	)
	(bus
		(pts
			(xy 279.4 104.14) (xy 304.8 104.14)
		)
		(stroke
			(width 0)
			(type default)
		)
	)
	(wire
		(pts
			(xy 279.4 106.68) (xy 304.8 106.68)
		)
		(stroke
			(width 0)
			(type default)
		)
	)
	(wire
		(pts
			(xy 355.6 210.82) (xy 358.14 210.82)
		)
		(stroke
			(width 0)
			(type default)
		)
	)
	(wire
		(pts
			(xy 76.2 162.56) (xy 152.4 162.56)
		)
		(stroke
			(width 0)
			(type default)
		)
	)
	(wire
		(pts
			(xy 300.99 137.16) (xy 300.99 124.46)
		)
		(stroke
			(width 0)
			(type default)
		)
	)
	(wire
		(pts
			(xy 317.5 218.44) (xy 317.5 226.06)
		)
		(stroke
			(width 0)
			(type default)
		)
	)
	(wire
		(pts
			(xy 300.99 124.46) (xy 304.8 124.46)
		)
		(stroke
			(width 0)
			(type default)
		)
	)
	(wire
		(pts
			(xy 320.04 203.2) (xy 317.5 203.2)
		)
		(stroke
			(width 0)
			(type default)
		)
	)
	(wire
		(pts
			(xy 317.5 210.82) (xy 320.04 210.82)
		)
		(stroke
			(width 0)
			(type default)
		)
	)
	(wire
		(pts
			(xy 355.6 210.82) (xy 355.6 218.44)
		)
		(stroke
			(width 0)
			(type default)
		)
	)
	(wire
		(pts
			(xy 317.5 210.82) (xy 317.5 218.44)
		)
		(stroke
			(width 0)
			(type default)
		)
	)
	(bus
		(pts
			(xy 76.2 167.64) (xy 152.4 167.64)
		)
		(stroke
			(width 0)
			(type default)
		)
	)
	(wire
		(pts
			(xy 203.2 106.68) (xy 228.6 106.68)
		)
		(stroke
			(width 0)
			(type default)
		)
	)
	(wire
		(pts
			(xy 279.4 119.38) (xy 304.8 119.38)
		)
		(stroke
			(width 0)
			(type default)
		)
	)
	(bus
		(pts
			(xy 127 119.38) (xy 152.4 119.38)
		)
		(stroke
			(width 0)
			(type default)
		)
	)
	(wire
		(pts
			(xy 358.14 226.06) (xy 355.6 226.06)
		)
		(stroke
			(width 0)
			(type default)
		)
	)
	(wire
		(pts
			(xy 358.14 203.2) (xy 355.6 203.2)
		)
		(stroke
			(width 0)
			(type default)
		)
	)
	(wire
		(pts
			(xy 203.2 119.38) (xy 228.6 119.38)
		)
		(stroke
			(width 0)
			(type default)
		)
	)
	(wire
		(pts
			(xy 203.2 137.16) (xy 300.99 137.16)
		)
		(stroke
			(width 0)
			(type default)
		)
	)
	(wire
		(pts
			(xy 203.2 109.22) (xy 228.6 109.22)
		)
		(stroke
			(width 0)
			(type default)
		)
	)
	(wire
		(pts
			(xy 320.04 226.06) (xy 317.5 226.06)
		)
		(stroke
			(width 0)
			(type default)
		)
	)
	(wire
		(pts
			(xy 149.86 160.02) (xy 152.4 160.02)
		)
		(stroke
			(width 0)
			(type default)
		)
	)
	(wire
		(pts
			(xy 355.6 218.44) (xy 358.14 218.44)
		)
		(stroke
			(width 0)
			(type default)
		)
	)
	(bus
		(pts
			(xy 203.2 104.14) (xy 228.6 104.14)
		)
		(stroke
			(width 0)
			(type default)
		)
	)
	(wire
		(pts
			(xy 317.5 203.2) (xy 317.5 210.82)
		)
		(stroke
			(width 0)
			(type default)
		)
	)
	(wire
		(pts
			(xy 88.9 157.48) (xy 76.2 157.48)
		)
		(stroke
			(width 0)
			(type default)
		)
	)
	(wire
		(pts
			(xy 304.8 111.76) (xy 298.45 111.76)
		)
		(stroke
			(width 0)
			(type default)
		)
	)
	(bus
		(pts
			(xy 279.4 116.84) (xy 304.8 116.84)
		)
		(stroke
			(width 0)
			(type default)
		)
	)
	(wire
		(pts
			(xy 279.4 121.92) (xy 304.8 121.92)
		)
		(stroke
			(width 0)
			(type default)
		)
	)
	(wire
		(pts
			(xy 101.6 95.25) (xy 88.9 95.25)
		)
		(stroke
			(width 0)
			(type default)
		)
	)
	(wire
		(pts
			(xy 355.6 226.06) (xy 355.6 228.6)
		)
		(stroke
			(width 0)
			(type default)
		)
	)
	(wire
		(pts
			(xy 149.86 137.16) (xy 149.86 160.02)
		)
		(stroke
			(width 0)
			(type default)
		)
	)
	(wire
		(pts
			(xy 298.45 111.76) (xy 298.45 134.62)
		)
		(stroke
			(width 0)
			(type default)
		)
	)
	(bus
		(pts
			(xy 76.2 170.18) (xy 152.4 170.18)
		)
		(stroke
			(width 0)
			(type default)
		)
	)
	(wire
		(pts
			(xy 317.5 218.44) (xy 320.04 218.44)
		)
		(stroke
			(width 0)
			(type default)
		)
	)
	(symbol
		(lib_id "antmicroMechanicalParts:MP_Pad6mm_Drill3.2mm")
		(at 320.04 218.44 0)
		(unit 1)
		(exclude_from_sim no)
		(in_bom no)
		(on_board yes)
		(dnp no)
		(fields_autoplaced yes)
		(property "Reference" "MP3"
			(at 328.93 217.17 0)
			(effects
				(font
					(size 1.27 1.27)
					(thickness 0.15)
				)
				(justify left)
			)
		)
		(property "Value" "MP_Pad6mm_Drill3.2mm"
			(at 328.93 219.71 0)
			(effects
				(font
					(size 1.27 1.27)
					(thickness 0.15)
				)
				(justify left)
			)
		)
		(property "Footprint" "antmicro-footprints:MP_Pad6mm_Drill3.2mm"
			(at 340.36 226.06 0)
			(effects
				(font
					(size 1.27 1.27)
					(thickness 0.15)
				)
				(justify left bottom)
				(hide yes)
			)
		)
		(property "Datasheet" ""
			(at 336.88 234.01 0)
			(effects
				(font
					(size 1.27 1.27)
					(thickness 0.15)
				)
				(justify left bottom)
				(hide yes)
			)
		)
		(property "Description" "Mechanical part"
			(at 320.04 218.44 0)
			(effects
				(font
					(size 1.27 1.27)
				)
				(hide yes)
			)
		)
		(property "Author" "Antmicro"
			(at 340.36 228.6 0)
			(effects
				(font
					(size 1.27 1.27)
					(thickness 0.15)
				)
				(justify left bottom)
				(hide yes)
			)
		)
		(property "License" "Apache-2.0"
			(at 340.36 231.14 0)
			(effects
				(font
					(size 1.27 1.27)
					(thickness 0.15)
				)
				(justify left bottom)
				(hide yes)
			)
		)
		(pin "1"
		)
		(instances
			(project "OCuLink to 10GbE adapter"
				(path ""
					(reference "MP3")
					(unit 1)
				)
			)
		)
	)
	(symbol
		(lib_id "antmicroMechanicalParts:MP_Pad6mm_Drill3.2mm")
		(at 358.14 203.2 0)
		(unit 1)
		(exclude_from_sim no)
		(in_bom no)
		(on_board yes)
		(dnp no)
		(fields_autoplaced yes)
		(property "Reference" "MP5"
			(at 367.03 201.93 0)
			(effects
				(font
					(size 1.27 1.27)
					(thickness 0.15)
				)
				(justify left)
			)
		)
		(property "Value" "MP_Pad6mm_Drill3.2mm"
			(at 367.03 204.47 0)
			(effects
				(font
					(size 1.27 1.27)
					(thickness 0.15)
				)
				(justify left)
			)
		)
		(property "Footprint" "antmicro-footprints:MP_Pad6mm_Drill3.2mm"
			(at 378.46 210.82 0)
			(effects
				(font
					(size 1.27 1.27)
					(thickness 0.15)
				)
				(justify left bottom)
				(hide yes)
			)
		)
		(property "Datasheet" ""
			(at 374.98 218.77 0)
			(effects
				(font
					(size 1.27 1.27)
					(thickness 0.15)
				)
				(justify left bottom)
				(hide yes)
			)
		)
		(property "Description" "Mechanical part"
			(at 358.14 203.2 0)
			(effects
				(font
					(size 1.27 1.27)
				)
				(hide yes)
			)
		)
		(property "Author" "Antmicro"
			(at 378.46 213.36 0)
			(effects
				(font
					(size 1.27 1.27)
					(thickness 0.15)
				)
				(justify left bottom)
				(hide yes)
			)
		)
		(property "License" "Apache-2.0"
			(at 378.46 215.9 0)
			(effects
				(font
					(size 1.27 1.27)
					(thickness 0.15)
				)
				(justify left bottom)
				(hide yes)
			)
		)
		(pin "1"
		)
		(instances
			(project "oculink-to-10gbe-adapter"
				(path ""
					(reference "MP5")
					(unit 1)
				)
			)
		)
	)
	(symbol
		(lib_id "antmicroMechanicalParts:MP_Pad6mm_Drill3.2mm")
		(at 358.14 226.06 0)
		(unit 1)
		(exclude_from_sim no)
		(in_bom no)
		(on_board yes)
		(dnp no)
		(fields_autoplaced yes)
		(property "Reference" "MP8"
			(at 367.03 224.79 0)
			(effects
				(font
					(size 1.27 1.27)
					(thickness 0.15)
				)
				(justify left)
			)
		)
		(property "Value" "MP_Pad6mm_Drill3.2mm"
			(at 367.03 227.33 0)
			(effects
				(font
					(size 1.27 1.27)
					(thickness 0.15)
				)
				(justify left)
			)
		)
		(property "Footprint" "antmicro-footprints:MP_Pad6mm_Drill3.2mm"
			(at 378.46 233.68 0)
			(effects
				(font
					(size 1.27 1.27)
					(thickness 0.15)
				)
				(justify left bottom)
				(hide yes)
			)
		)
		(property "Datasheet" ""
			(at 374.98 241.63 0)
			(effects
				(font
					(size 1.27 1.27)
					(thickness 0.15)
				)
				(justify left bottom)
				(hide yes)
			)
		)
		(property "Description" "Mechanical part"
			(at 358.14 226.06 0)
			(effects
				(font
					(size 1.27 1.27)
				)
				(hide yes)
			)
		)
		(property "Author" "Antmicro"
			(at 378.46 236.22 0)
			(effects
				(font
					(size 1.27 1.27)
					(thickness 0.15)
				)
				(justify left bottom)
				(hide yes)
			)
		)
		(property "License" "Apache-2.0"
			(at 378.46 238.76 0)
			(effects
				(font
					(size 1.27 1.27)
					(thickness 0.15)
				)
				(justify left bottom)
				(hide yes)
			)
		)
		(pin "1"
		)
		(instances
			(project "oculink-to-10gbe-adapter"
				(path ""
					(reference "MP8")
					(unit 1)
				)
			)
		)
	)
	(symbol
		(lib_id "antmicroMechanicalParts:MP_Pad6mm_Drill3.2mm")
		(at 358.14 210.82 0)
		(unit 1)
		(exclude_from_sim no)
		(in_bom no)
		(on_board yes)
		(dnp no)
		(fields_autoplaced yes)
		(property "Reference" "MP6"
			(at 367.03 209.55 0)
			(effects
				(font
					(size 1.27 1.27)
					(thickness 0.15)
				)
				(justify left)
			)
		)
		(property "Value" "MP_Pad6mm_Drill3.2mm"
			(at 367.03 212.09 0)
			(effects
				(font
					(size 1.27 1.27)
					(thickness 0.15)
				)
				(justify left)
			)
		)
		(property "Footprint" "antmicro-footprints:MP_Pad6mm_Drill3.2mm"
			(at 378.46 218.44 0)
			(effects
				(font
					(size 1.27 1.27)
					(thickness 0.15)
				)
				(justify left bottom)
				(hide yes)
			)
		)
		(property "Datasheet" ""
			(at 374.98 226.39 0)
			(effects
				(font
					(size 1.27 1.27)
					(thickness 0.15)
				)
				(justify left bottom)
				(hide yes)
			)
		)
		(property "Description" "Mechanical part"
			(at 358.14 210.82 0)
			(effects
				(font
					(size 1.27 1.27)
				)
				(hide yes)
			)
		)
		(property "Author" "Antmicro"
			(at 378.46 220.98 0)
			(effects
				(font
					(size 1.27 1.27)
					(thickness 0.15)
				)
				(justify left bottom)
				(hide yes)
			)
		)
		(property "License" "Apache-2.0"
			(at 378.46 223.52 0)
			(effects
				(font
					(size 1.27 1.27)
					(thickness 0.15)
				)
				(justify left bottom)
				(hide yes)
			)
		)
		(pin "1"
		)
		(instances
			(project "oculink-to-10gbe-adapter"
				(path ""
					(reference "MP6")
					(unit 1)
				)
			)
		)
	)
	(symbol
		(lib_id "antmicroMechanicalParts:MP_Pad6mm_Drill3.2mm")
		(at 320.04 203.2 0)
		(unit 1)
		(exclude_from_sim no)
		(in_bom no)
		(on_board yes)
		(dnp no)
		(fields_autoplaced yes)
		(property "Reference" "MP1"
			(at 328.93 201.93 0)
			(effects
				(font
					(size 1.27 1.27)
					(thickness 0.15)
				)
				(justify left)
			)
		)
		(property "Value" "MP_Pad6mm_Drill3.2mm"
			(at 328.93 204.47 0)
			(effects
				(font
					(size 1.27 1.27)
					(thickness 0.15)
				)
				(justify left)
			)
		)
		(property "Footprint" "antmicro-footprints:MP_Pad6mm_Drill3.2mm"
			(at 340.36 210.82 0)
			(effects
				(font
					(size 1.27 1.27)
					(thickness 0.15)
				)
				(justify left bottom)
				(hide yes)
			)
		)
		(property "Datasheet" ""
			(at 336.88 218.77 0)
			(effects
				(font
					(size 1.27 1.27)
					(thickness 0.15)
				)
				(justify left bottom)
				(hide yes)
			)
		)
		(property "Description" "Mechanical part"
			(at 320.04 203.2 0)
			(effects
				(font
					(size 1.27 1.27)
				)
				(hide yes)
			)
		)
		(property "Author" "Antmicro"
			(at 340.36 213.36 0)
			(effects
				(font
					(size 1.27 1.27)
					(thickness 0.15)
				)
				(justify left bottom)
				(hide yes)
			)
		)
		(property "License" "Apache-2.0"
			(at 340.36 215.9 0)
			(effects
				(font
					(size 1.27 1.27)
					(thickness 0.15)
				)
				(justify left bottom)
				(hide yes)
			)
		)
		(pin "1"
		)
		(instances
			(project ""
				(path ""
					(reference "MP1")
					(unit 1)
				)
			)
		)
	)
	(symbol
		(lib_id "antmicroMechanicalParts:MP_Pad6mm_Drill3.2mm")
		(at 320.04 226.06 0)
		(unit 1)
		(exclude_from_sim no)
		(in_bom no)
		(on_board yes)
		(dnp no)
		(fields_autoplaced yes)
		(property "Reference" "MP4"
			(at 328.93 224.79 0)
			(effects
				(font
					(size 1.27 1.27)
					(thickness 0.15)
				)
				(justify left)
			)
		)
		(property "Value" "MP_Pad6mm_Drill3.2mm"
			(at 328.93 227.33 0)
			(effects
				(font
					(size 1.27 1.27)
					(thickness 0.15)
				)
				(justify left)
			)
		)
		(property "Footprint" "antmicro-footprints:MP_Pad6mm_Drill3.2mm"
			(at 340.36 233.68 0)
			(effects
				(font
					(size 1.27 1.27)
					(thickness 0.15)
				)
				(justify left bottom)
				(hide yes)
			)
		)
		(property "Datasheet" ""
			(at 336.88 241.63 0)
			(effects
				(font
					(size 1.27 1.27)
					(thickness 0.15)
				)
				(justify left bottom)
				(hide yes)
			)
		)
		(property "Description" "Mechanical part"
			(at 320.04 226.06 0)
			(effects
				(font
					(size 1.27 1.27)
				)
				(hide yes)
			)
		)
		(property "Author" "Antmicro"
			(at 340.36 236.22 0)
			(effects
				(font
					(size 1.27 1.27)
					(thickness 0.15)
				)
				(justify left bottom)
				(hide yes)
			)
		)
		(property "License" "Apache-2.0"
			(at 340.36 238.76 0)
			(effects
				(font
					(size 1.27 1.27)
					(thickness 0.15)
				)
				(justify left bottom)
				(hide yes)
			)
		)
		(pin "1"
		)
		(instances
			(project "OCuLink to 10GbE adapter"
				(path ""
					(reference "MP4")
					(unit 1)
				)
			)
		)
	)
	(symbol
		(lib_id "antmicroMechanicalParts:MP_Pad6mm_Drill3.2mm")
		(at 320.04 210.82 0)
		(unit 1)
		(exclude_from_sim no)
		(in_bom no)
		(on_board yes)
		(dnp no)
		(fields_autoplaced yes)
		(property "Reference" "MP2"
			(at 328.93 209.55 0)
			(effects
				(font
					(size 1.27 1.27)
					(thickness 0.15)
				)
				(justify left)
			)
		)
		(property "Value" "MP_Pad6mm_Drill3.2mm"
			(at 328.93 212.09 0)
			(effects
				(font
					(size 1.27 1.27)
					(thickness 0.15)
				)
				(justify left)
			)
		)
		(property "Footprint" "antmicro-footprints:MP_Pad6mm_Drill3.2mm"
			(at 340.36 218.44 0)
			(effects
				(font
					(size 1.27 1.27)
					(thickness 0.15)
				)
				(justify left bottom)
				(hide yes)
			)
		)
		(property "Datasheet" ""
			(at 336.88 226.39 0)
			(effects
				(font
					(size 1.27 1.27)
					(thickness 0.15)
				)
				(justify left bottom)
				(hide yes)
			)
		)
		(property "Description" "Mechanical part"
			(at 320.04 210.82 0)
			(effects
				(font
					(size 1.27 1.27)
				)
				(hide yes)
			)
		)
		(property "Author" "Antmicro"
			(at 340.36 220.98 0)
			(effects
				(font
					(size 1.27 1.27)
					(thickness 0.15)
				)
				(justify left bottom)
				(hide yes)
			)
		)
		(property "License" "Apache-2.0"
			(at 340.36 223.52 0)
			(effects
				(font
					(size 1.27 1.27)
					(thickness 0.15)
				)
				(justify left bottom)
				(hide yes)
			)
		)
		(pin "1"
		)
		(instances
			(project "OCuLink to 10GbE adapter"
				(path ""
					(reference "MP2")
					(unit 1)
				)
			)
		)
	)
	(symbol
		(lib_id "antmicroMechanicalParts:MP_Pad6mm_Drill3.2mm")
		(at 358.14 218.44 0)
		(unit 1)
		(exclude_from_sim no)
		(in_bom no)
		(on_board yes)
		(dnp no)
		(fields_autoplaced yes)
		(property "Reference" "MP7"
			(at 367.03 217.17 0)
			(effects
				(font
					(size 1.27 1.27)
					(thickness 0.15)
				)
				(justify left)
			)
		)
		(property "Value" "MP_Pad6mm_Drill3.2mm"
			(at 367.03 219.71 0)
			(effects
				(font
					(size 1.27 1.27)
					(thickness 0.15)
				)
				(justify left)
			)
		)
		(property "Footprint" "antmicro-footprints:MP_Pad6mm_Drill3.2mm"
			(at 378.46 226.06 0)
			(effects
				(font
					(size 1.27 1.27)
					(thickness 0.15)
				)
				(justify left bottom)
				(hide yes)
			)
		)
		(property "Datasheet" ""
			(at 374.98 234.01 0)
			(effects
				(font
					(size 1.27 1.27)
					(thickness 0.15)
				)
				(justify left bottom)
				(hide yes)
			)
		)
		(property "Description" "Mechanical part"
			(at 358.14 218.44 0)
			(effects
				(font
					(size 1.27 1.27)
				)
				(hide yes)
			)
		)
		(property "Author" "Antmicro"
			(at 378.46 228.6 0)
			(effects
				(font
					(size 1.27 1.27)
					(thickness 0.15)
				)
				(justify left bottom)
				(hide yes)
			)
		)
		(property "License" "Apache-2.0"
			(at 378.46 231.14 0)
			(effects
				(font
					(size 1.27 1.27)
					(thickness 0.15)
				)
				(justify left bottom)
				(hide yes)
			)
		)
		(pin "1"
		)
		(instances
			(project "oculink-to-10gbe-adapter"
				(path ""
					(reference "MP7")
					(unit 1)
				)
			)
		)
	)
	(symbol
		(lib_id "antmicroMechanicalParts:Heatsink_ATS-61500R-C2-R0")
		(at 336.55 168.91 0)
		(unit 1)
		(exclude_from_sim no)
		(in_bom no)
		(on_board yes)
		(dnp yes)
		(fields_autoplaced yes)
		(property "Reference" "H1"
			(at 342.9 169.8625 0)
			(effects
				(font
					(size 1.27 1.27)
					(thickness 0.15)
				)
				(justify left)
			)
		)
		(property "Value" "Heatsink_ATS-61500R-C2-R0"
			(at 342.9 172.4025 0)
			(effects
				(font
					(size 1.27 1.27)
					(thickness 0.15)
				)
				(justify left)
				(hide yes)
			)
		)
		(property "Footprint" "antmicro-footprints:Heatsink_ATS-61500R-C2-R0"
			(at 354.33 176.53 0)
			(effects
				(font
					(size 1.27 1.27)
					(thickness 0.15)
				)
				(justify left bottom)
				(hide yes)
			)
		)
		(property "Datasheet" "https://www.qats.com/DataSheet/ATS-61500-Series-C2-R0"
			(at 354.33 179.07 0)
			(effects
				(font
					(size 1.27 1.27)
					(thickness 0.15)
				)
				(justify left bottom)
				(hide yes)
			)
		)
		(property "Description" "Heat Sinks fanSINK Assembly with Mounting Hardware"
			(at 336.55 168.91 0)
			(effects
				(font
					(size 1.27 1.27)
				)
				(hide yes)
			)
		)
		(property "MPN" "ATS-61500R-C2-R0"
			(at 342.9 172.4025 0)
			(effects
				(font
					(size 1.27 1.27)
					(thickness 0.15)
				)
				(justify left)
			)
		)
		(property "Manufacturer" "Advanced Thermal Solutions"
			(at 354.33 184.15 0)
			(effects
				(font
					(size 1.27 1.27)
					(thickness 0.15)
				)
				(justify left bottom)
				(hide yes)
			)
		)
		(property "Author" "Antmicro"
			(at 354.33 186.69 0)
			(effects
				(font
					(size 1.27 1.27)
					(thickness 0.15)
				)
				(justify left bottom)
				(hide yes)
			)
		)
		(property "License" "Apache-2.0"
			(at 354.33 189.23 0)
			(effects
				(font
					(size 1.27 1.27)
					(thickness 0.15)
				)
				(justify left bottom)
				(hide yes)
			)
		)
		(instances
			(project "OCuLink to 10GbE adapter"
				(path ""
					(reference "H1")
					(unit 1)
				)
			)
		)
	)
	(symbol
		(lib_id "antmicropower:GND")
		(at 355.6 228.6 0)
		(unit 1)
		(exclude_from_sim no)
		(in_bom yes)
		(on_board yes)
		(dnp no)
		(property "Reference" "#PWR063"
			(at 364.49 231.14 0)
			(effects
				(font
					(size 1.27 1.27)
					(thickness 0.15)
				)
				(justify left bottom)
				(hide yes)
			)
		)
		(property "Value" "GND"
			(at 355.6 232.41 0)
			(effects
				(font
					(size 1.27 1.27)
					(thickness 0.15)
				)
			)
		)
		(property "Footprint" ""
			(at 364.49 236.22 0)
			(effects
				(font
					(size 1.27 1.27)
					(thickness 0.15)
				)
				(justify left bottom)
				(hide yes)
			)
		)
		(property "Datasheet" ""
			(at 364.49 241.3 0)
			(effects
				(font
					(size 1.27 1.27)
					(thickness 0.15)
				)
				(justify left bottom)
				(hide yes)
			)
		)
		(property "Description" ""
			(at 355.6 228.6 0)
			(effects
				(font
					(size 1.27 1.27)
				)
				(hide yes)
			)
		)
		(property "Author" "Antmicro"
			(at 364.49 236.22 0)
			(effects
				(font
					(size 1.27 1.27)
					(thickness 0.15)
				)
				(justify left bottom)
				(hide yes)
			)
		)
		(property "License" "Apache-2.0"
			(at 364.49 238.76 0)
			(effects
				(font
					(size 1.27 1.27)
					(thickness 0.15)
				)
				(justify left bottom)
				(hide yes)
			)
		)
		(pin "1"
		)
		(instances
			(project "oculink-to-10gbe-adapter"
				(path ""
					(reference "#PWR063")
					(unit 1)
				)
			)
		)
	)
	(symbol
		(lib_id "antmicropower:GND")
		(at 317.5 228.6 0)
		(unit 1)
		(exclude_from_sim no)
		(in_bom yes)
		(on_board yes)
		(dnp no)
		(property "Reference" "#PWR01"
			(at 326.39 231.14 0)
			(effects
				(font
					(size 1.27 1.27)
					(thickness 0.15)
				)
				(justify left bottom)
				(hide yes)
			)
		)
		(property "Value" "GND"
			(at 317.5 232.41 0)
			(effects
				(font
					(size 1.27 1.27)
					(thickness 0.15)
				)
			)
		)
		(property "Footprint" ""
			(at 326.39 236.22 0)
			(effects
				(font
					(size 1.27 1.27)
					(thickness 0.15)
				)
				(justify left bottom)
				(hide yes)
			)
		)
		(property "Datasheet" ""
			(at 326.39 241.3 0)
			(effects
				(font
					(size 1.27 1.27)
					(thickness 0.15)
				)
				(justify left bottom)
				(hide yes)
			)
		)
		(property "Description" ""
			(at 317.5 228.6 0)
			(effects
				(font
					(size 1.27 1.27)
				)
				(hide yes)
			)
		)
		(property "Author" "Antmicro"
			(at 326.39 236.22 0)
			(effects
				(font
					(size 1.27 1.27)
					(thickness 0.15)
				)
				(justify left bottom)
				(hide yes)
			)
		)
		(property "License" "Apache-2.0"
			(at 326.39 238.76 0)
			(effects
				(font
					(size 1.27 1.27)
					(thickness 0.15)
				)
				(justify left bottom)
				(hide yes)
			)
		)
		(pin "1"
		)
		(instances
			(project "OCuLink to 10GbE adapter"
				(path ""
					(reference "#PWR01")
					(unit 1)
				)
			)
		)
	)
	(sheet
		(at 50.8 127)
		(size 25.4 50.8)
		(exclude_from_sim no)
		(in_bom yes)
		(on_board yes)
		(dnp no)
		(fields_autoplaced yes)
		(stroke
			(width 0.1524)
			(type solid)
		)
		(fill
			(color 255 255 194 1.0000)
		)
		(property "Sheetname" "OCuLink"
			(at 50.8 126.2884 0)
			(effects
				(font
					(size 1.27 1.27)
				)
				(justify left bottom)
			)
		)
		(property "Sheetfile" "oculink.kicad_sch"
			(at 50.8 178.3846 0)
			(effects
				(font
					(size 1.27 1.27)
				)
				(justify left top)
			)
		)
		(pin "~{PE_RST}" output
			(at 76.2 160.02 0)
			(effects
				(font
					(size 1.27 1.27)
				)
				(justify right)
			)
		)
		(pin "SMBus{I2C}" bidirectional
			(at 76.2 134.62 0)
			(effects
				(font
					(size 1.27 1.27)
				)
				(justify right)
			)
		)
		(pin "~{CPRSNT}" input
			(at 76.2 157.48 0)
			(effects
				(font
					(size 1.27 1.27)
				)
				(justify right)
			)
		)
		(pin "PCIe_{x4}{PCIe}" bidirectional
			(at 76.2 167.64 0)
			(effects
				(font
					(size 1.27 1.27)
				)
				(justify right)
			)
		)
		(pin "REFCLK{CLK}" output
			(at 76.2 170.18 0)
			(effects
				(font
					(size 1.27 1.27)
				)
				(justify right)
			)
		)
		(pin "~{PE_WAKE}" input
			(at 76.2 162.56 0)
			(effects
				(font
					(size 1.27 1.27)
				)
				(justify right)
			)
		)
		(instances
			(project "oculink-to-10gbe-adapter"
				(path ""
					(page "11")
				)
			)
		)
	)
	(sheet
		(at 152.4 157.48)
		(size 50.8 20.32)
		(exclude_from_sim no)
		(in_bom yes)
		(on_board yes)
		(dnp no)
		(fields_autoplaced yes)
		(stroke
			(width 0.1524)
			(type solid)
		)
		(fill
			(color 255 255 194 1.0000)
		)
		(property "Sheetname" "X710-AT2 PCIe"
			(at 152.4 156.7684 0)
			(effects
				(font
					(size 1.27 1.27)
				)
				(justify left bottom)
			)
		)
		(property "Sheetfile" "x710-at2-pcie.kicad_sch"
			(at 152.4 178.3846 0)
			(effects
				(font
					(size 1.27 1.27)
				)
				(justify left top)
			)
		)
		(pin "~{PE_RST}" input
			(at 152.4 160.02 180)
			(effects
				(font
					(size 1.27 1.27)
				)
				(justify left)
			)
		)
		(pin "REFCLK{CLK}" input
			(at 152.4 170.18 180)
			(effects
				(font
					(size 1.27 1.27)
				)
				(justify left)
			)
		)
		(pin "PCIe_{x4}{PCIe}" bidirectional
			(at 152.4 167.64 180)
			(effects
				(font
					(size 1.27 1.27)
				)
				(justify left)
			)
		)
		(pin "~{PE_WAKE}" output
			(at 152.4 162.56 180)
			(effects
				(font
					(size 1.27 1.27)
				)
				(justify left)
			)
		)
		(instances
			(project "oculink-to-10gbe-adapter"
				(path ""
					(page "7")
				)
			)
		)
	)
	(sheet
		(at 101.6 88.9)
		(size 25.4 12.7)
		(exclude_from_sim no)
		(in_bom yes)
		(on_board yes)
		(dnp no)
		(fields_autoplaced yes)
		(stroke
			(width 0.1524)
			(type solid)
		)
		(fill
			(color 255 255 194 1.0000)
		)
		(property "Sheetname" "Power"
			(at 101.6 88.1884 0)
			(effects
				(font
					(size 1.27 1.27)
				)
				(justify left bottom)
			)
		)
		(property "Sheetfile" "power.kicad_sch"
			(at 101.6 102.1846 0)
			(effects
				(font
					(size 1.27 1.27)
				)
				(justify left top)
			)
		)
		(pin "~{CPRSNT}" output
			(at 101.6 95.25 180)
			(effects
				(font
					(size 1.27 1.27)
				)
				(justify left)
			)
		)
		(instances
			(project "oculink-to-10gbe-adapter"
				(path ""
					(page "2")
				)
			)
		)
	)
	(sheet
		(at 228.6 101.6)
		(size 50.8 22.86)
		(exclude_from_sim no)
		(in_bom yes)
		(on_board yes)
		(dnp no)
		(fields_autoplaced yes)
		(stroke
			(width 0.1524)
			(type solid)
		)
		(fill
			(color 255 255 194 1.0000)
		)
		(property "Sheetname" "X710-AT2 10GbE"
			(at 228.6 100.8884 0)
			(effects
				(font
					(size 1.27 1.27)
				)
				(justify left bottom)
			)
		)
		(property "Sheetfile" "x710-at2-10gbe.kicad_sch"
			(at 228.6 125.0446 0)
			(effects
				(font
					(size 1.27 1.27)
				)
				(justify left top)
			)
		)
		(pin "MDIO0_I2C0{MDIO}" bidirectional
			(at 228.6 104.14 180)
			(effects
				(font
					(size 1.27 1.27)
				)
				(justify left)
			)
		)
		(pin "~{P0_INT}" input
			(at 228.6 106.68 180)
			(effects
				(font
					(size 1.27 1.27)
				)
				(justify left)
			)
		)
		(pin "~{P0_LED_ACT}" output
			(at 279.4 106.68 0)
			(effects
				(font
					(size 1.27 1.27)
				)
				(justify right)
			)
		)
		(pin "~{P0_LED_LINK_10G}" output
			(at 279.4 109.22 0)
			(effects
				(font
					(size 1.27 1.27)
				)
				(justify right)
			)
		)
		(pin "~{P1_LED_ACT}" output
			(at 279.4 119.38 0)
			(effects
				(font
					(size 1.27 1.27)
				)
				(justify right)
			)
		)
		(pin "~{P1_LED_LINK_10G}" output
			(at 279.4 121.92 0)
			(effects
				(font
					(size 1.27 1.27)
				)
				(justify right)
			)
		)
		(pin "~{P1_INT}" input
			(at 228.6 109.22 180)
			(effects
				(font
					(size 1.27 1.27)
				)
				(justify left)
			)
		)
		(pin "~{PHY_RESET_3V3}" output
			(at 228.6 119.38 180)
			(effects
				(font
					(size 1.27 1.27)
				)
				(justify left)
			)
		)
		(pin "Ethernet_P0{10GbE}" bidirectional
			(at 279.4 104.14 0)
			(effects
				(font
					(size 1.27 1.27)
				)
				(justify right)
			)
		)
		(pin "Ethernet_P1{10GbE}" bidirectional
			(at 279.4 116.84 0)
			(effects
				(font
					(size 1.27 1.27)
				)
				(justify right)
			)
		)
		(instances
			(project "oculink-to-10gbe-adapter"
				(path ""
					(page "8")
				)
			)
		)
	)
	(sheet
		(at 228.6 144.78)
		(size 50.8 12.7)
		(exclude_from_sim no)
		(in_bom yes)
		(on_board yes)
		(dnp no)
		(fields_autoplaced yes)
		(stroke
			(width 0.1524)
			(type solid)
		)
		(fill
			(color 255 255 194 1.0000)
		)
		(property "Sheetname" "X710-AT2 RSVD"
			(at 228.6 144.0684 0)
			(effects
				(font
					(size 1.27 1.27)
				)
				(justify left bottom)
			)
		)
		(property "Sheetfile" "x710-at2-rsvd.kicad_sch"
			(at 228.6 158.0646 0)
			(effects
				(font
					(size 1.27 1.27)
				)
				(justify left top)
			)
		)
		(instances
			(project "oculink-to-10gbe-adapter"
				(path ""
					(page "10")
				)
			)
		)
	)
	(sheet
		(at 228.6 165.1)
		(size 50.8 12.7)
		(exclude_from_sim no)
		(in_bom yes)
		(on_board yes)
		(dnp no)
		(fields_autoplaced yes)
		(stroke
			(width 0.1524)
			(type solid)
		)
		(fill
			(color 255 255 194 1.0000)
		)
		(property "Sheetname" "X710-AT2 power"
			(at 228.6 164.3884 0)
			(effects
				(font
					(size 1.27 1.27)
				)
				(justify left bottom)
			)
		)
		(property "Sheetfile" "x710-at2-power.kicad_sch"
			(at 228.6 178.3846 0)
			(effects
				(font
					(size 1.27 1.27)
				)
				(justify left top)
			)
		)
		(instances
			(project "oculink-to-10gbe-adapter"
				(path ""
					(page "6")
				)
			)
		)
	)
	(sheet
		(at 304.8 101.6)
		(size 38.1 25.4)
		(exclude_from_sim no)
		(in_bom yes)
		(on_board yes)
		(dnp no)
		(fields_autoplaced yes)
		(stroke
			(width 0.1016)
			(type solid)
		)
		(fill
			(color 255 255 194 1.0000)
		)
		(property "Sheetname" "2xRJ45"
			(at 304.8 100.9138 0)
			(effects
				(font
					(size 1.27 1.27)
				)
				(justify left bottom)
			)
		)
		(property "Sheetfile" "2xrj45.kicad_sch"
			(at 304.8 127.5592 0)
			(effects
				(font
					(size 1.27 1.27)
				)
				(justify left top)
			)
		)
		(pin "~{P0_LED_ACT}" input
			(at 304.8 106.68 180)
			(effects
				(font
					(size 1.27 1.27)
				)
				(justify left)
			)
		)
		(pin "~{P0_LED_LINK_10G}" input
			(at 304.8 109.22 180)
			(effects
				(font
					(size 1.27 1.27)
				)
				(justify left)
			)
		)
		(pin "~{P0_LINK_LESS_THAN_10G}" input
			(at 304.8 111.76 180)
			(effects
				(font
					(size 1.27 1.27)
				)
				(justify left)
			)
		)
		(pin "~{P1_LED_ACT}" input
			(at 304.8 119.38 180)
			(effects
				(font
					(size 1.27 1.27)
				)
				(justify left)
			)
		)
		(pin "~{P1_LED_LINK_10G}" input
			(at 304.8 121.92 180)
			(effects
				(font
					(size 1.27 1.27)
				)
				(justify left)
			)
		)
		(pin "~{P1_LINK_LESS_THAN_10G}" input
			(at 304.8 124.46 180)
			(effects
				(font
					(size 1.27 1.27)
				)
				(justify left)
			)
		)
		(pin "Ethernet_P0{10GbE}" bidirectional
			(at 304.8 104.14 180)
			(effects
				(font
					(size 1.27 1.27)
				)
				(justify left)
			)
		)
		(pin "Ethernet_P1{10GbE}" bidirectional
			(at 304.8 116.84 180)
			(effects
				(font
					(size 1.27 1.27)
				)
				(justify left)
			)
		)
		(instances
			(project "oculink-to-10gbe-adapter"
				(path ""
					(page "4")
				)
			)
		)
	)
	(sheet
		(at 101.6 113.03)
		(size 25.4 12.7)
		(exclude_from_sim no)
		(in_bom yes)
		(on_board yes)
		(dnp no)
		(fields_autoplaced yes)
		(stroke
			(width 0.1524)
			(type solid)
		)
		(fill
			(color 255 255 194 1.0000)
		)
		(property "Sheetname" "Flash memory"
			(at 101.6 112.3184 0)
			(effects
				(font
					(size 1.27 1.27)
				)
				(justify left bottom)
			)
		)
		(property "Sheetfile" "flash-memory.kicad_sch"
			(at 101.6 126.3146 0)
			(effects
				(font
					(size 1.27 1.27)
				)
				(justify left top)
			)
		)
		(pin "FLASH{SPI}" bidirectional
			(at 127 119.38 0)
			(effects
				(font
					(size 1.27 1.27)
				)
				(justify right)
			)
		)
		(instances
			(project "oculink-to-10gbe-adapter"
				(path ""
					(page "3")
				)
			)
		)
	)
	(sheet
		(at 304.8 165.1)
		(size 25.4 12.7)
		(exclude_from_sim no)
		(in_bom no)
		(on_board yes)
		(dnp yes)
		(fields_autoplaced yes)
		(stroke
			(width 0.1524)
			(type solid)
		)
		(fill
			(color 255 255 194 1.0000)
		)
		(property "Sheetname" "Fan controller"
			(at 304.8 164.3884 0)
			(effects
				(font
					(size 1.27 1.27)
				)
				(justify left bottom)
			)
		)
		(property "Sheetfile" "fan-controller.kicad_sch"
			(at 304.8 178.3846 0)
			(effects
				(font
					(size 1.27 1.27)
				)
				(justify left top)
			)
		)
		(instances
			(project "oculink-to-10gbe-adapter"
				(path ""
					(page "13")
				)
			)
		)
	)
	(sheet
		(at 152.4 101.6)
		(size 50.8 38.1)
		(exclude_from_sim no)
		(in_bom yes)
		(on_board yes)
		(dnp no)
		(fields_autoplaced yes)
		(stroke
			(width 0.1524)
			(type solid)
		)
		(fill
			(color 255 255 194 1.0000)
		)
		(property "Sheetname" "X710-AT2 Misc"
			(at 152.4 100.8884 0)
			(effects
				(font
					(size 1.27 1.27)
				)
				(justify left bottom)
			)
		)
		(property "Sheetfile" "x710-at2-mics.kicad_sch"
			(at 152.4 140.2846 0)
			(effects
				(font
					(size 1.27 1.27)
				)
				(justify left top)
			)
		)
		(pin "SMBus{I2C}" bidirectional
			(at 152.4 134.62 180)
			(effects
				(font
					(size 1.27 1.27)
				)
				(justify left)
			)
		)
		(pin "FLASH{SPI}" bidirectional
			(at 152.4 119.38 180)
			(effects
				(font
					(size 1.27 1.27)
				)
				(justify left)
			)
		)
		(pin "~{PE_RST}" input
			(at 152.4 137.16 180)
			(effects
				(font
					(size 1.27 1.27)
				)
				(justify left)
			)
		)
		(pin "~{P0_LINK_LESS_THAN_10G}" output
			(at 203.2 134.62 0)
			(effects
				(font
					(size 1.27 1.27)
				)
				(justify right)
			)
		)
		(pin "~{P1_LINK_LESS_THAN_10G}" output
			(at 203.2 137.16 0)
			(effects
				(font
					(size 1.27 1.27)
				)
				(justify right)
			)
		)
		(pin "P0_INT_MLC" output
			(at 203.2 106.68 0)
			(effects
				(font
					(size 1.27 1.27)
				)
				(justify right)
			)
		)
		(pin "P1_INT_MLC" output
			(at 203.2 109.22 0)
			(effects
				(font
					(size 1.27 1.27)
				)
				(justify right)
			)
		)
		(pin "MDIO_I2C{MDIO}" bidirectional
			(at 203.2 104.14 0)
			(effects
				(font
					(size 1.27 1.27)
				)
				(justify right)
			)
		)
		(pin "~{PHY_RESET_3V3}" input
			(at 203.2 119.38 0)
			(effects
				(font
					(size 1.27 1.27)
				)
				(justify right)
			)
		)
		(instances
			(project "oculink-to-10gbe-adapter"
				(path ""
					(page "9")
				)
			)
		)
	)
	(sheet_instances
		(path "/"
			(page "1")
		)
	)
)
